(kicad_pcb
	(version 20260206)
	(generator "pcbnew")
	(generator_version "10.0")
	(general
		(thickness 1.6)
		(legacy_teardrops no)
	)
	(paper "A4")
	(title_block
		(title "baseboard — 13948-1b.1110WZS1818.brd")
		(comment 1 "Honey Badger (Wiwynn) / footprints 618-625 of 2523")
	)
	(layers
		(0 "F.Cu" signal "TOP")
		(4 "In1.Cu" signal "L2GND")
		(6 "In2.Cu" signal "L3")
		(8 "In3.Cu" signal "L4VCC")
		(10 "In4.Cu" signal "L5VCC")
		(12 "In5.Cu" signal "L6")
		(14 "In6.Cu" signal "L7GND")
		(2 "B.Cu" signal "BOTTOM")
		(9 "F.Adhes" user "F.Adhesive")
		(11 "B.Adhes" user "B.Adhesive")
		(13 "F.Paste" user "Package Geometry/Pastemask Top")
		(15 "B.Paste" user "Package Geometry/Pastemask Bottom")
		(5 "F.SilkS" user "Ref Des/Silkscreen Top")
		(7 "B.SilkS" user "Ref Des/Silkscreen Bottom")
		(1 "F.Mask" user "Board Geometry/Soldermask Top")
		(3 "B.Mask" user "Board Geometry/Soldermask Bottom")
		(17 "Dwgs.User" user "User.Drawings")
		(19 "Cmts.User" user "User.Comments")
		(21 "Eco1.User" user "User.Eco1")
		(23 "Eco2.User" user "User.Eco2")
		(25 "Edge.Cuts" user "Board Geometry/Outline")
		(27 "Margin" user)
		(31 "F.CrtYd" user "Package Geometry/Place Bound Top")
		(29 "B.CrtYd" user "Package Geometry/Place Bound Bottom")
		(35 "F.Fab" user "Ref Des/Assembly Top")
		(33 "B.Fab" user "Ref Des/Assembly Bottom")
	)
	(footprint ""
		(layer "F.Cu")
		(at 41.03497 -139.827 90)
		(property "Reference" "SR916"
			(at 0 0 90)
			(layer "F.SilkS")
			(hide yes)
			(effects
				(font
					(size 1.27 1.27)
				)
			)
		)
		(property "Value" "4K7R2F-GP"
			(at 0.064008 -3.993896 90)
			(unlocked yes)
			(layer "F.Fab")
			(hide yes)
			(effects
				(font
					(size 1.016 1.016)
					(thickness 0.1524)
				)
			)
		)
		(property "Device Type" "R402H16"
			(at 0.064008 -5.517896 90)
			(unlocked yes)
			(layer "F.Fab")
			(hide yes)
			(effects
				(font
					(size 1.016 1.016)
					(thickness 0.1524)
				)
			)
		)
		(duplicate_pad_numbers_are_jumpers no)
		(fp_line
			(start 0.508 -0.9398)
			(end -0.508 -0.9398)
			(stroke
				(width 0.1524)
				(type default)
			)
			(layer "F.SilkS")
		)
		(fp_line
			(start -0.508 -0.9398)
			(end -0.508 0.9398)
			(stroke
				(width 0.1524)
				(type default)
			)
			(layer "F.SilkS")
		)
		(fp_rect
			(start -0.508 0.9398)
			(end 0.508 -0.9398)
			(stroke
				(width 0)
				(type default)
			)
			(fill no)
			(layer "F.CrtYd")
		)
		(fp_rect
			(start -0.508 0.9398)
			(end 0.508 -0.9398)
			(stroke
				(width 0)
				(type default)
			)
			(fill no)
			(layer "F.Fab")
		)
		(pad "1" smd custom
			(at 0 -0.4445 90)
			(size 0.1397 0.1397)
			(layers "F.Cu" "F.Mask" "F.Paste")
			(net "P3V3_STBY")
			(options
				(clearance outline)
				(anchor circle)
			)
			(primitives
				(gr_poly
					(pts
						(arc
							(start -0.1778 -0.2794)
							(mid -0.249642 -0.249642)
							(end -0.2794 -0.1778)
						)
						(arc
							(start -0.2794 0.1778)
							(mid -0.249642 0.249642)
							(end -0.1778 0.2794)
						)
						(arc
							(start 0.1778 0.2794)
							(mid 0.249642 0.249642)
							(end 0.2794 0.1778)
						)
						(arc
							(start 0.2794 -0.1778)
							(mid 0.249642 -0.249642)
							(end 0.1778 -0.2794)
						)
					)
					(width 0)
					(fill yes)
				)
			)
		)
		(pad "2" smd custom
			(at 0 0.4445 90)
			(size 0.1397 0.1397)
			(layers "F.Cu" "F.Mask" "F.Paste")
			(net "BMC_RST_EXPANDER")
			(options
				(clearance outline)
				(anchor circle)
			)
			(primitives
				(gr_poly
					(pts
						(arc
							(start -0.1778 -0.2794)
							(mid -0.249642 -0.249642)
							(end -0.2794 -0.1778)
						)
						(arc
							(start -0.2794 0.1778)
							(mid -0.249642 0.249642)
							(end -0.1778 0.2794)
						)
						(arc
							(start 0.1778 0.2794)
							(mid 0.249642 0.249642)
							(end 0.2794 0.1778)
						)
						(arc
							(start 0.2794 -0.1778)
							(mid 0.249642 -0.249642)
							(end 0.1778 -0.2794)
						)
					)
					(width 0)
					(fill yes)
				)
			)
		)
	)
	(footprint ""
		(layer "F.Cu")
		(at 200.279 -167.64 180)
		(property "Reference" "C321"
			(at 0 0 180)
			(layer "F.SilkS")
			(hide yes)
			(effects
				(font
					(size 1.27 1.27)
				)
			)
		)
		(property "Value" "SCD1U16V2KX-3GP"
			(at 1.1811 -2.7051 180)
			(unlocked yes)
			(layer "F.Fab")
			(hide yes)
			(effects
				(font
					(size 1.016 1.016)
					(thickness 0.1524)
				)
			)
		)
		(property "Device Type" "C402H22"
			(at 1.1811 -4.2291 180)
			(unlocked yes)
			(layer "F.Fab")
			(hide yes)
			(effects
				(font
					(size 1.016 1.016)
					(thickness 0.1524)
				)
			)
		)
		(duplicate_pad_numbers_are_jumpers no)
		(fp_rect
			(start -0.4318 0.9525)
			(end 0.4318 -0.9525)
			(stroke
				(width 0)
				(type default)
			)
			(fill no)
			(layer "F.CrtYd")
		)
		(fp_rect
			(start -0.4318 0.9525)
			(end 0.4318 -0.9525)
			(stroke
				(width 0)
				(type default)
			)
			(fill no)
			(layer "F.Fab")
		)
		(pad "1" smd custom
			(at 0 -0.4445 180)
			(size 0.1524 0.1524)
			(layers "F.Cu" "F.Mask" "F.Paste")
			(net "P3V3_B")
			(options
				(clearance outline)
				(anchor circle)
			)
			(primitives
				(gr_poly
					(pts
						(arc
							(start 0.3048 -0.2032)
							(mid 0.275042 -0.275042)
							(end 0.2032 -0.3048)
						)
						(arc
							(start -0.2032 -0.3048)
							(mid -0.275042 -0.275042)
							(end -0.3048 -0.2032)
						)
						(arc
							(start -0.3048 0.2032)
							(mid -0.275042 0.275042)
							(end -0.2032 0.3048)
						)
						(arc
							(start 0.2032 0.3048)
							(mid 0.275042 0.275042)
							(end 0.3048 0.2032)
						)
					)
					(width 0)
					(fill yes)
				)
			)
		)
		(pad "2" smd custom
			(at 0 0.4445 180)
			(size 0.1524 0.1524)
			(layers "F.Cu" "F.Mask" "F.Paste")
			(net "GND")
			(options
				(clearance outline)
				(anchor circle)
			)
			(primitives
				(gr_poly
					(pts
						(arc
							(start 0.3048 -0.2032)
							(mid 0.275042 -0.275042)
							(end 0.2032 -0.3048)
						)
						(arc
							(start -0.2032 -0.3048)
							(mid -0.275042 -0.275042)
							(end -0.3048 -0.2032)
						)
						(arc
							(start -0.3048 0.2032)
							(mid -0.275042 0.275042)
							(end -0.2032 0.3048)
						)
						(arc
							(start 0.2032 0.3048)
							(mid 0.275042 0.275042)
							(end 0.3048 0.2032)
						)
					)
					(width 0)
					(fill yes)
				)
			)
		)
	)
	(footprint ""
		(layer "F.Cu")
		(at 208.407 -99.06 -90)
		(property "Reference" "PC143"
			(at 0 0 270)
			(layer "F.SilkS")
			(hide yes)
			(effects
				(font
					(size 1.27 1.27)
				)
			)
		)
		(property "Value" "SC10U6D3V5KX-1GP"
			(at -0.0762 -6.1214 270)
			(unlocked yes)
			(layer "F.Fab")
			(hide yes)
			(effects
				(font
					(size 1.016 1.016)
					(thickness 0.1524)
				)
			)
		)
		(property "Device Type" "C805H54"
			(at -0.0762 -8.1534 270)
			(unlocked yes)
			(layer "F.Fab")
			(hide yes)
			(effects
				(font
					(size 1.016 1.016)
					(thickness 0.1524)
				)
			)
		)
		(duplicate_pad_numbers_are_jumpers no)
		(fp_line
			(start 0.635 0)
			(end -0.635 0)
			(stroke
				(width 0.508)
				(type default)
			)
			(layer "F.SilkS")
		)
		(fp_rect
			(start -0.9652 1.778)
			(end 0.9652 -1.778)
			(stroke
				(width 0)
				(type default)
			)
			(fill no)
			(layer "F.CrtYd")
		)
		(fp_poly
			(pts
				(xy -0.9652 -1.778) (xy 0.9652 -1.778) (xy 0.9652 1.778) (xy -0.9652 1.778)
			)
			(stroke
				(width 0)
				(type default)
			)
			(fill no)
			(layer "F.Fab")
		)
		(pad "1" smd rect
			(at 0 -0.9652 270)
			(size 1.397 1.143)
			(layers "F.Cu" "F.Mask" "F.Paste")
			(net "P1V5_C")
		)
		(pad "2" smd rect
			(at 0 0.9652 270)
			(size 1.397 1.143)
			(layers "F.Cu" "F.Mask" "F.Paste")
			(net "GND")
		)
	)
	(footprint ""
		(layer "F.Cu")
		(at 180.721 -144.272 -90)
		(property "Reference" "SC1295"
			(at 0 0 270)
			(layer "F.SilkS")
			(hide yes)
			(effects
				(font
					(size 1.27 1.27)
				)
			)
		)
		(property "Value" "SCD1U16V2KX-3GP"
			(at 1.1811 -2.7051 270)
			(unlocked yes)
			(layer "F.Fab")
			(hide yes)
			(effects
				(font
					(size 1.016 1.016)
					(thickness 0.1524)
				)
			)
		)
		(property "Device Type" "C402H22"
			(at 1.1811 -4.2291 270)
			(unlocked yes)
			(layer "F.Fab")
			(hide yes)
			(effects
				(font
					(size 1.016 1.016)
					(thickness 0.1524)
				)
			)
		)
		(duplicate_pad_numbers_are_jumpers no)
		(fp_rect
			(start -0.4318 0.9525)
			(end 0.4318 -0.9525)
			(stroke
				(width 0)
				(type default)
			)
			(fill no)
			(layer "F.CrtYd")
		)
		(fp_rect
			(start -0.4318 0.9525)
			(end 0.4318 -0.9525)
			(stroke
				(width 0)
				(type default)
			)
			(fill no)
			(layer "F.Fab")
		)
		(pad "1" smd custom
			(at 0 -0.4445 270)
			(size 0.1524 0.1524)
			(layers "F.Cu" "F.Mask" "F.Paste")
			(net "EXP_I2C_VREF_3")
			(options
				(clearance outline)
				(anchor circle)
			)
			(primitives
				(gr_poly
					(pts
						(arc
							(start 0.3048 -0.2032)
							(mid 0.275042 -0.275042)
							(end 0.2032 -0.3048)
						)
						(arc
							(start -0.2032 -0.3048)
							(mid -0.275042 -0.275042)
							(end -0.3048 -0.2032)
						)
						(arc
							(start -0.3048 0.2032)
							(mid -0.275042 0.275042)
							(end -0.2032 0.3048)
						)
						(arc
							(start 0.2032 0.3048)
							(mid 0.275042 0.275042)
							(end 0.3048 0.2032)
						)
					)
					(width 0)
					(fill yes)
				)
			)
		)
		(pad "2" smd custom
			(at 0 0.4445 270)
			(size 0.1524 0.1524)
			(layers "F.Cu" "F.Mask" "F.Paste")
			(net "GND")
			(options
				(clearance outline)
				(anchor circle)
			)
			(primitives
				(gr_poly
					(pts
						(arc
							(start 0.3048 -0.2032)
							(mid 0.275042 -0.275042)
							(end 0.2032 -0.3048)
						)
						(arc
							(start -0.2032 -0.3048)
							(mid -0.275042 -0.275042)
							(end -0.3048 -0.2032)
						)
						(arc
							(start -0.3048 0.2032)
							(mid -0.275042 0.275042)
							(end -0.2032 0.3048)
						)
						(arc
							(start 0.2032 0.3048)
							(mid 0.275042 0.275042)
							(end 0.3048 0.2032)
						)
					)
					(width 0)
					(fill yes)
				)
			)
		)
	)
	(footprint ""
		(layer "F.Cu")
		(at 178.816 -221.869)
		(property "Reference" "U172"
			(at 0 0 0)
			(layer "F.SilkS")
			(hide yes)
			(effects
				(font
					(size 1.27 1.27)
				)
			)
		)
		(property "Value" "SN74LVC1G08DCKR-GP"
			(at -2.3368 -8.6868 0)
			(unlocked yes)
			(layer "F.Fab")
			(hide yes)
			(effects
				(font
					(size 1.016 1.016)
					(thickness 0.1524)
				)
			)
		)
		(property "Device Type" "SC70-5H44"
			(at -2.3114 -10.414 0)
			(unlocked yes)
			(layer "F.Fab")
			(hide yes)
			(effects
				(font
					(size 1.016 1.016)
					(thickness 0.1524)
				)
			)
		)
		(duplicate_pad_numbers_are_jumpers no)
		(fp_line
			(start -1.27 -1.7018)
			(end 1.27 -1.7018)
			(stroke
				(width 0.1524)
				(type default)
			)
			(layer "F.SilkS")
		)
		(fp_line
			(start -1.27 1.7018)
			(end -1.27 -1.7018)
			(stroke
				(width 0.1524)
				(type default)
			)
			(layer "F.SilkS")
		)
		(fp_line
			(start 0.6604 -1.8034)
			(end 1.3843 -1.8034)
			(stroke
				(width 0.3302)
				(type default)
			)
			(layer "F.SilkS")
		)
		(fp_line
			(start 1.27 -1.7018)
			(end 1.27 1.7018)
			(stroke
				(width 0.1524)
				(type default)
			)
			(layer "F.SilkS")
		)
		(fp_line
			(start 1.27 1.7018)
			(end -1.27 1.7018)
			(stroke
				(width 0.1524)
				(type default)
			)
			(layer "F.SilkS")
		)
		(fp_line
			(start 1.3843 -1.8034)
			(end 1.3843 -1.1176)
			(stroke
				(width 0.3302)
				(type default)
			)
			(layer "F.SilkS")
		)
		(fp_rect
			(start -1.524 1.9558)
			(end 1.524 -1.9558)
			(stroke
				(width 0)
				(type default)
			)
			(fill no)
			(layer "F.CrtYd")
		)
		(fp_poly
			(pts
				(xy -1.524 -1.9558) (xy 1.524 -1.9558) (xy 1.524 1.9558) (xy -1.524 1.9558)
			)
			(stroke
				(width 0)
				(type default)
			)
			(fill no)
			(layer "F.Fab")
		)
		(pad "1" smd rect
			(at 0.65024 -0.8255)
			(size 0.4064 1.2192)
			(layers "F.Cu" "F.Mask" "F.Paste")
			(net "PWRBTN_OUT_N")
		)
		(pad "2" smd rect
			(at 0 -0.8255)
			(size 0.4064 1.2192)
			(layers "F.Cu" "F.Mask" "F.Paste")
			(net "BMC_PWRBTN_N")
		)
		(pad "3" smd rect
			(at -0.65024 -0.8255)
			(size 0.4064 1.2192)
			(layers "F.Cu" "F.Mask" "F.Paste")
			(net "GND")
		)
		(pad "4" smd rect
			(at -0.65024 0.8255)
			(size 0.4064 1.2192)
			(layers "F.Cu" "F.Mask" "F.Paste")
			(net "PMU_PWRBTN_N")
		)
		(pad "5" smd rect
			(at 0.65024 0.8255)
			(size 0.4064 1.2192)
			(layers "F.Cu" "F.Mask" "F.Paste")
			(net "P3V3_STBY")
		)
	)
	(footprint ""
		(layer "F.Cu")
		(at 327.787 -92.202 -90)
		(property "Reference" "PC35"
			(at 0 0 270)
			(layer "F.SilkS")
			(hide yes)
			(effects
				(font
					(size 1.27 1.27)
				)
			)
		)
		(property "Value" "SCD1U16V3KX-3GP"
			(at 0 -2.8194 270)
			(unlocked yes)
			(layer "F.Fab")
			(hide yes)
			(effects
				(font
					(size 1.016 1.016)
					(thickness 0.1524)
				)
			)
		)
		(property "Device Type" "C603H36"
			(at 0 -4.3434 270)
			(unlocked yes)
			(layer "F.Fab")
			(hide yes)
			(effects
				(font
					(size 1.016 1.016)
					(thickness 0.1524)
				)
			)
		)
		(duplicate_pad_numbers_are_jumpers no)
		(fp_line
			(start 0.508 0)
			(end -0.508 0)
			(stroke
				(width 0.2032)
				(type default)
			)
			(layer "F.SilkS")
		)
		(fp_rect
			(start -0.5842 1.3335)
			(end 0.5842 -1.3335)
			(stroke
				(width 0)
				(type default)
			)
			(fill no)
			(layer "F.CrtYd")
		)
		(fp_rect
			(start -0.5842 1.3335)
			(end 0.5842 -1.3335)
			(stroke
				(width 0)
				(type default)
			)
			(fill no)
			(layer "F.Fab")
		)
		(pad "1" smd custom
			(at 0 -0.762 270)
			(size 0.2159 0.2159)
			(layers "F.Cu" "F.Mask" "F.Paste")
			(net "P3V3_STBY")
			(options
				(clearance outline)
				(anchor circle)
			)
			(primitives
				(gr_poly
					(pts
						(arc
							(start -0.3302 -0.4318)
							(mid -0.402042 -0.402042)
							(end -0.4318 -0.3302)
						)
						(arc
							(start -0.4318 0.3302)
							(mid -0.402042 0.402042)
							(end -0.3302 0.4318)
						)
						(arc
							(start 0.3302 0.4318)
							(mid 0.402042 0.402042)
							(end 0.4318 0.3302)
						)
						(arc
							(start 0.4318 -0.3302)
							(mid 0.402042 -0.402042)
							(end 0.3302 -0.4318)
						)
					)
					(width 0)
					(fill yes)
				)
			)
		)
		(pad "2" smd custom
			(at 0 0.762 270)
			(size 0.2159 0.2159)
			(layers "F.Cu" "F.Mask" "F.Paste")
			(net "GND")
			(options
				(clearance outline)
				(anchor circle)
			)
			(primitives
				(gr_poly
					(pts
						(arc
							(start -0.3302 -0.4318)
							(mid -0.402042 -0.402042)
							(end -0.4318 -0.3302)
						)
						(arc
							(start -0.4318 0.3302)
							(mid -0.402042 0.402042)
							(end -0.3302 0.4318)
						)
						(arc
							(start 0.3302 0.4318)
							(mid 0.402042 0.402042)
							(end 0.4318 0.3302)
						)
						(arc
							(start 0.4318 -0.3302)
							(mid 0.402042 -0.402042)
							(end 0.3302 -0.4318)
						)
					)
					(width 0)
					(fill yes)
				)
			)
		)
	)
	(footprint ""
		(layer "F.Cu")
		(at 107.88777 -71.9328 90)
		(property "Reference" "R586"
			(at 0 0 90)
			(layer "F.SilkS")
			(hide yes)
			(effects
				(font
					(size 1.27 1.27)
				)
			)
		)
		(property "Value" "4K7R2F-GP"
			(at 0.064008 -3.993896 90)
			(unlocked yes)
			(layer "F.Fab")
			(hide yes)
			(effects
				(font
					(size 1.016 1.016)
					(thickness 0.1524)
				)
			)
		)
		(property "Device Type" "R402H16"
			(at 0.064008 -5.517896 90)
			(unlocked yes)
			(layer "F.Fab")
			(hide yes)
			(effects
				(font
					(size 1.016 1.016)
					(thickness 0.1524)
				)
			)
		)
		(duplicate_pad_numbers_are_jumpers no)
		(fp_line
			(start 0.508 -0.9398)
			(end -0.508 -0.9398)
			(stroke
				(width 0.1524)
				(type default)
			)
			(layer "F.SilkS")
		)
		(fp_line
			(start -0.508 -0.9398)
			(end -0.508 0.9398)
			(stroke
				(width 0.1524)
				(type default)
			)
			(layer "F.SilkS")
		)
		(fp_rect
			(start -0.508 0.9398)
			(end 0.508 -0.9398)
			(stroke
				(width 0)
				(type default)
			)
			(fill no)
			(layer "F.CrtYd")
		)
		(fp_rect
			(start -0.508 0.9398)
			(end 0.508 -0.9398)
			(stroke
				(width 0)
				(type default)
			)
			(fill no)
			(layer "F.Fab")
		)
		(pad "1" smd custom
			(at 0 -0.4445 90)
			(size 0.1397 0.1397)
			(layers "F.Cu" "F.Mask" "F.Paste")
			(net "P3V3_STBY")
			(options
				(clearance outline)
				(anchor circle)
			)
			(primitives
				(gr_poly
					(pts
						(arc
							(start -0.1778 -0.2794)
							(mid -0.249642 -0.249642)
							(end -0.2794 -0.1778)
						)
						(arc
							(start -0.2794 0.1778)
							(mid -0.249642 0.249642)
							(end -0.1778 0.2794)
						)
						(arc
							(start 0.1778 0.2794)
							(mid 0.249642 0.249642)
							(end 0.2794 0.1778)
						)
						(arc
							(start 0.2794 -0.1778)
							(mid 0.249642 -0.249642)
							(end 0.1778 -0.2794)
						)
					)
					(width 0)
					(fill yes)
				)
			)
		)
		(pad "2" smd custom
			(at 0 0.4445 90)
			(size 0.1397 0.1397)
			(layers "F.Cu" "F.Mask" "F.Paste")
			(net "TEMP_4_A1")
			(options
				(clearance outline)
				(anchor circle)
			)
			(primitives
				(gr_poly
					(pts
						(arc
							(start -0.1778 -0.2794)
							(mid -0.249642 -0.249642)
							(end -0.2794 -0.1778)
						)
						(arc
							(start -0.2794 0.1778)
							(mid -0.249642 0.249642)
							(end -0.1778 0.2794)
						)
						(arc
							(start 0.1778 0.2794)
							(mid 0.249642 0.249642)
							(end 0.2794 0.1778)
						)
						(arc
							(start 0.2794 -0.1778)
							(mid 0.249642 -0.249642)
							(end 0.1778 -0.2794)
						)
					)
					(width 0)
					(fill yes)
				)
			)
		)
	)
	(footprint ""
		(layer "F.Cu")
		(at 340.516718 -158.473648 90)
		(property "Reference" "R547"
			(at 0 0 90)
			(layer "F.SilkS")
			(hide yes)
			(effects
				(font
					(size 1.27 1.27)
				)
			)
		)
		(property "Value" "4K7R2F-GP"
			(at 0.064008 -3.993896 90)
			(unlocked yes)
			(layer "F.Fab")
			(hide yes)
			(effects
				(font
					(size 1.016 1.016)
					(thickness 0.1524)
				)
			)
		)
		(property "Device Type" "R402H16"
			(at 0.064008 -5.517896 90)
			(unlocked yes)
			(layer "F.Fab")
			(hide yes)
			(effects
				(font
					(size 1.016 1.016)
					(thickness 0.1524)
				)
			)
		)
		(duplicate_pad_numbers_are_jumpers no)
		(fp_line
			(start 0.508 -0.9398)
			(end -0.508 -0.9398)
			(stroke
				(width 0.1524)
				(type default)
			)
			(layer "F.SilkS")
		)
		(fp_line
			(start -0.508 -0.9398)
			(end -0.508 0.9398)
			(stroke
				(width 0.1524)
				(type default)
			)
			(layer "F.SilkS")
		)
		(fp_rect
			(start -0.508 0.9398)
			(end 0.508 -0.9398)
			(stroke
				(width 0)
				(type default)
			)
			(fill no)
			(layer "F.CrtYd")
		)
		(fp_rect
			(start -0.508 0.9398)
			(end 0.508 -0.9398)
			(stroke
				(width 0)
				(type default)
			)
			(fill no)
			(layer "F.Fab")
		)
		(pad "1" smd custom
			(at 0 -0.4445 90)
			(size 0.1397 0.1397)
			(layers "F.Cu" "F.Mask" "F.Paste")
			(net "USB_EN_2")
			(options
				(clearance outline)
				(anchor circle)
			)
			(primitives
				(gr_poly
					(pts
						(arc
							(start -0.1778 -0.2794)
							(mid -0.249642 -0.249642)
							(end -0.2794 -0.1778)
						)
						(arc
							(start -0.2794 0.1778)
							(mid -0.249642 0.249642)
							(end -0.1778 0.2794)
						)
						(arc
							(start 0.1778 0.2794)
							(mid 0.249642 0.249642)
							(end 0.2794 0.1778)
						)
						(arc
							(start 0.2794 -0.1778)
							(mid 0.249642 -0.249642)
							(end 0.1778 -0.2794)
						)
					)
					(width 0)
					(fill yes)
				)
			)
		)
		(pad "2" smd custom
			(at 0 0.4445 90)
			(size 0.1397 0.1397)
			(layers "F.Cu" "F.Mask" "F.Paste")
			(net "GND")
			(options
				(clearance outline)
				(anchor circle)
			)
			(primitives
				(gr_poly
					(pts
						(arc
							(start -0.1778 -0.2794)
							(mid -0.249642 -0.249642)
							(end -0.2794 -0.1778)
						)
						(arc
							(start -0.2794 0.1778)
							(mid -0.249642 0.249642)
							(end -0.1778 0.2794)
						)
						(arc
							(start 0.1778 0.2794)
							(mid 0.249642 0.249642)
							(end 0.2794 0.1778)
						)
						(arc
							(start 0.2794 -0.1778)
							(mid 0.249642 -0.249642)
							(end 0.1778 -0.2794)
						)
					)
					(width 0)
					(fill yes)
				)
			)
		)
	)
)
